# T6G (Grand Teton) — schematic netlist excerpt (pin names and nets, part order shuffled) for the footprints in the layout excerpt that follows; sources: Cadence DE-HDL packaged netlist, KiCad conversion of 04192023_DAF0TMB3IC0_F0TG_MB_C_brd_V02_OCP.brd

C1068  Q_CAP  0.1UF 10V 10% X7S  pkg C0201  page 186 : A = P3V3_AUX ; B = GND
C2570  Q_CAP  22UF 4V 20% X6S  pkg C0402  page 70 : A = PVDDCR_SOC_P0 ; B = GND
C283  Q_CAP  0.1UF 10V 10% X7S  pkg C0201  page 323 : A = P0V9_CPU1_RT0_2A ; B = GND

(kicad_pcb
	(version 20260206)
	(generator "pcbnew")
	(generator_version "10.0")
	(general
		(thickness 1.6)
		(legacy_teardrops no)
	)
	(paper "A4")
	(title_block
		(title "04192023_DAF0TMB3IC0_F0TG_MB_C_brd_V02_OCP.brd")
		(comment 1 "Grand Teton / footprints 8297-8299 of 8354")
	)
	(layers
		(0 "F.Cu" signal "TOP")
		(4 "In1.Cu" signal "GND")
		(6 "In2.Cu" signal "IN1")
		(8 "In3.Cu" signal "GND1")
		(10 "In4.Cu" signal "IN2")
		(12 "In5.Cu" signal "GND2")
		(14 "In6.Cu" signal "IN3")
		(16 "In7.Cu" signal "GND3")
		(18 "In8.Cu" signal "VCC")
		(20 "In9.Cu" signal "VCC1")
		(22 "In10.Cu" signal "GND4")
		(24 "In11.Cu" signal "IN4")
		(26 "In12.Cu" signal "GND5")
		(28 "In13.Cu" signal "IN5")
		(30 "In14.Cu" signal "GND6")
		(32 "In15.Cu" signal "IN6")
		(34 "In16.Cu" signal "GND7")
		(2 "B.Cu" signal "BOTTOM")
		(9 "F.Adhes" user "F.Adhesive")
		(11 "B.Adhes" user "B.Adhesive")
		(13 "F.Paste" user "Package Geometry/Pastemask Top")
		(15 "B.Paste" user "Package Geometry/Pastemask Bottom")
		(5 "F.SilkS" user "Ref Des/Silkscreen Top")
		(7 "B.SilkS" user "Ref Des/Silkscreen Bottom")
		(1 "F.Mask" user "Board Geometry/Soldermask Top")
		(3 "B.Mask" user "Board Geometry/Soldermask Bottom")
		(17 "Dwgs.User" user "User.Drawings")
		(19 "Cmts.User" user "User.Comments")
		(21 "Eco1.User" user "User.Eco1")
		(23 "Eco2.User" user "User.Eco2")
		(25 "Edge.Cuts" user "Board Geometry/Outline")
		(27 "Margin" user)
		(31 "F.CrtYd" user "Package Geometry/Place Bound Top")
		(29 "B.CrtYd" user "Package Geometry/Place Bound Bottom")
		(35 "F.Fab" user "Ref Des/Assembly Top")
		(33 "B.Fab" user "Ref Des/Assembly Bottom")
	)
	(footprint ""
		(layer "B.Cu")
		(at 61.918596 -388.011162 -90)
		(property "Reference" "C283"
			(at 0 0 90)
			(layer "B.SilkS")
			(hide yes)
			(effects
				(font
					(size 1.27 1.27)
				)
				(justify mirror)
			)
		)
		(property "Value" ""
			(at 0 0 90)
			(layer "B.Fab")
			(effects
				(font
					(size 1.27 1.27)
				)
				(justify mirror)
			)
		)
		(duplicate_pad_numbers_are_jumpers no)
		(fp_line
			(start -0.299974 0.150114)
			(end 0.299974 0.150114)
			(stroke
				(width 0.1)
				(type default)
			)
			(layer "B.Fab")
		)
		(fp_line
			(start 0.299974 0.150114)
			(end 0.299974 -0.150114)
			(stroke
				(width 0.1)
				(type default)
			)
			(layer "B.Fab")
		)
		(fp_line
			(start -0.299974 -0.150114)
			(end -0.299974 0.150114)
			(stroke
				(width 0.1)
				(type default)
			)
			(layer "B.Fab")
		)
		(fp_line
			(start 0.299974 -0.150114)
			(end -0.299974 -0.150114)
			(stroke
				(width 0.1)
				(type default)
			)
			(layer "B.Fab")
		)
		(pad "1" smd rect
			(at 0.2667 0 90)
			(size 0.3048 0.381)
			(layers "B.Cu" "B.Mask" "B.Paste")
			(net "P0V9_CPU1_RT0_2A")
		)
		(pad "2" smd rect
			(at -0.2667 0 90)
			(size 0.3048 0.381)
			(layers "B.Cu" "B.Mask" "B.Paste")
			(net "GND")
		)
	)
	(footprint ""
		(layer "B.Cu")
		(at 159.931608 -415.531046)
		(property "Reference" "C1068"
			(at 0 0 0)
			(layer "B.SilkS")
			(hide yes)
			(effects
				(font
					(size 1.27 1.27)
				)
				(justify mirror)
			)
		)
		(property "Value" ""
			(at 0 0 0)
			(layer "B.Fab")
			(effects
				(font
					(size 1.27 1.27)
				)
				(justify mirror)
			)
		)
		(duplicate_pad_numbers_are_jumpers no)
		(fp_line
			(start -0.299974 -0.150114)
			(end -0.299974 0.150114)
			(stroke
				(width 0.1)
				(type default)
			)
			(layer "B.Fab")
		)
		(fp_line
			(start -0.299974 0.150114)
			(end 0.299974 0.150114)
			(stroke
				(width 0.1)
				(type default)
			)
			(layer "B.Fab")
		)
		(fp_line
			(start 0.299974 -0.150114)
			(end -0.299974 -0.150114)
			(stroke
				(width 0.1)
				(type default)
			)
			(layer "B.Fab")
		)
		(fp_line
			(start 0.299974 0.150114)
			(end 0.299974 -0.150114)
			(stroke
				(width 0.1)
				(type default)
			)
			(layer "B.Fab")
		)
		(pad "1" smd rect
			(at 0.2667 0 180)
			(size 0.3048 0.381)
			(layers "B.Cu" "B.Mask" "B.Paste")
			(net "P3V3_AUX")
		)
		(pad "2" smd rect
			(at -0.2667 0 180)
			(size 0.3048 0.381)
			(layers "B.Cu" "B.Mask" "B.Paste")
			(net "GND")
		)
	)
	(footprint ""
		(layer "B.Cu")
		(at 372.6815 -261.935976)
		(property "Reference" "C2570"
			(at 0 0 0)
			(layer "B.SilkS")
			(hide yes)
			(effects
				(font
					(size 1.27 1.27)
				)
				(justify mirror)
			)
		)
		(property "Value" ""
			(at 0 0 0)
			(layer "B.Fab")
			(effects
				(font
					(size 1.27 1.27)
				)
				(justify mirror)
			)
		)
		(duplicate_pad_numbers_are_jumpers no)
		(fp_line
			(start -0.7874 -0.4064)
			(end -0.7874 0.4064)
			(stroke
				(width 0.1524)
				(type default)
			)
			(layer "B.SilkS")
		)
		(fp_line
			(start -0.7874 0.4064)
			(end 0.7874 0.4064)
			(stroke
				(width 0.1524)
				(type default)
			)
			(layer "B.SilkS")
		)
		(fp_line
			(start 0.7874 -0.4064)
			(end -0.7874 -0.4064)
			(stroke
				(width 0.1524)
				(type default)
			)
			(layer "B.SilkS")
		)
		(fp_line
			(start 0.7874 0.4064)
			(end 0.7874 -0.4064)
			(stroke
				(width 0.1524)
				(type default)
			)
			(layer "B.SilkS")
		)
		(fp_line
			(start -0.67945 -0.3048)
			(end -0.67945 0.3048)
			(stroke
				(width 0.1)
				(type default)
			)
			(layer "B.Fab")
		)
		(fp_line
			(start -0.67945 0.3048)
			(end -0.120396 0.3048)
			(stroke
				(width 0.1)
				(type default)
			)
			(layer "B.Fab")
		)
		(fp_line
			(start -0.12065 -0.3048)
			(end -0.67945 -0.3048)
			(stroke
				(width 0.1)
				(type default)
			)
			(layer "B.Fab")
		)
		(fp_line
			(start -0.12065 -0.2794)
			(end -0.12065 -0.3048)
			(stroke
				(width 0.1)
				(type default)
			)
			(layer "B.Fab")
		)
		(fp_line
			(start -0.120396 0.2794)
			(end 0.12065 0.2794)
			(stroke
				(width 0.1)
				(type default)
			)
			(layer "B.Fab")
		)
		(fp_line
			(start -0.120396 0.3048)
			(end -0.120396 0.2794)
			(stroke
				(width 0.1)
				(type default)
			)
			(layer "B.Fab")
		)
		(fp_line
			(start 0.12065 -0.305054)
			(end 0.12065 -0.2794)
			(stroke
				(width 0.1)
				(type default)
			)
			(layer "B.Fab")
		)
		(fp_line
			(start 0.12065 -0.2794)
			(end -0.12065 -0.2794)
			(stroke
				(width 0.1)
				(type default)
			)
			(layer "B.Fab")
		)
		(fp_line
			(start 0.12065 0.2794)
			(end 0.12065 0.3048)
			(stroke
				(width 0.1)
				(type default)
			)
			(layer "B.Fab")
		)
		(fp_line
			(start 0.12065 0.3048)
			(end 0.67945 0.3048)
			(stroke
				(width 0.1)
				(type default)
			)
			(layer "B.Fab")
		)
		(fp_line
			(start 0.67945 -0.305054)
			(end 0.12065 -0.305054)
			(stroke
				(width 0.1)
				(type default)
			)
			(layer "B.Fab")
		)
		(fp_line
			(start 0.67945 0.3048)
			(end 0.67945 -0.305054)
			(stroke
				(width 0.1)
				(type default)
			)
			(layer "B.Fab")
		)
		(pad "1" smd circle
			(at 0.40005 0 180)
			(size 0 0)
			(layers "B.Cu" "B.Mask" "B.Paste")
			(net "PVDDCR_SOC_P0")
		)
		(pad "2" smd circle
			(at -0.40005 0 180)
			(size 0 0)
			(layers "B.Cu" "B.Mask" "B.Paste")
			(net "GND")
		)
	)
)
